# T6G (Grand Teton) — schematic netlist excerpt (pin names and nets, part order shuffled) for the footprints in the layout excerpt that follows; sources: Cadence DE-HDL packaged netlist, KiCad conversion of 04192023_DAF0TMB3IC0_F0TG_MB_C_brd_V02_OCP.brd

PR6804  Q_RES  1K 1% EMPTY  pkg 0402LF  page 364 : A = P3V3_AUX ; B = P0V9_RETIMER_CPU1_SVID_SDA
PR3780  Q_RES  5.36K 1% CHIP  pkg 0402LF  page 134 : A = P3V3_OCP_CB_1 ; B = GND

(kicad_pcb
	(version 20260206)
	(generator "pcbnew")
	(generator_version "10.0")
	(general
		(thickness 1.6)
		(legacy_teardrops no)
	)
	(paper "A4")
	(title_block
		(title "04192023_DAF0TMB3IC0_F0TG_MB_C_brd_V02_OCP.brd")
		(comment 1 "Grand Teton / footprints 3295-3296 of 8354")
	)
	(layers
		(0 "F.Cu" signal "TOP")
		(4 "In1.Cu" signal "GND")
		(6 "In2.Cu" signal "IN1")
		(8 "In3.Cu" signal "GND1")
		(10 "In4.Cu" signal "IN2")
		(12 "In5.Cu" signal "GND2")
		(14 "In6.Cu" signal "IN3")
		(16 "In7.Cu" signal "GND3")
		(18 "In8.Cu" signal "VCC")
		(20 "In9.Cu" signal "VCC1")
		(22 "In10.Cu" signal "GND4")
		(24 "In11.Cu" signal "IN4")
		(26 "In12.Cu" signal "GND5")
		(28 "In13.Cu" signal "IN5")
		(30 "In14.Cu" signal "GND6")
		(32 "In15.Cu" signal "IN6")
		(34 "In16.Cu" signal "GND7")
		(2 "B.Cu" signal "BOTTOM")
		(9 "F.Adhes" user "F.Adhesive")
		(11 "B.Adhes" user "B.Adhesive")
		(13 "F.Paste" user "Package Geometry/Pastemask Top")
		(15 "B.Paste" user "Package Geometry/Pastemask Bottom")
		(5 "F.SilkS" user "Ref Des/Silkscreen Top")
		(7 "B.SilkS" user "Ref Des/Silkscreen Bottom")
		(1 "F.Mask" user "Board Geometry/Soldermask Top")
		(3 "B.Mask" user "Board Geometry/Soldermask Bottom")
		(17 "Dwgs.User" user "User.Drawings")
		(19 "Cmts.User" user "User.Comments")
		(21 "Eco1.User" user "User.Eco1")
		(23 "Eco2.User" user "User.Eco2")
		(25 "Edge.Cuts" user "Board Geometry/Outline")
		(27 "Margin" user)
		(31 "F.CrtYd" user "Package Geometry/Place Bound Top")
		(29 "B.CrtYd" user "Package Geometry/Place Bound Bottom")
		(35 "F.Fab" user "Ref Des/Assembly Top")
		(33 "B.Fab" user "Ref Des/Assembly Bottom")
	)
	(footprint ""
		(layer "F.Cu")
		(at 20.480782 -411.707584 180)
		(property "Reference" "PR6804"
			(at 0 0 180)
			(layer "F.SilkS")
			(hide yes)
			(effects
				(font
					(size 1.27 1.27)
				)
			)
		)
		(property "Value" ""
			(at 0 0 180)
			(layer "F.Fab")
			(effects
				(font
					(size 1.27 1.27)
				)
			)
		)
		(duplicate_pad_numbers_are_jumpers no)
		(fp_line
			(start 0.7874 0.4064)
			(end -0.7874 0.4064)
			(stroke
				(width 0.1524)
				(type default)
			)
			(layer "F.SilkS")
		)
		(fp_line
			(start 0.7874 -0.4064)
			(end 0.7874 0.4064)
			(stroke
				(width 0.1524)
				(type default)
			)
			(layer "F.SilkS")
		)
		(fp_line
			(start -0.7874 0.4064)
			(end -0.7874 -0.4064)
			(stroke
				(width 0.1524)
				(type default)
			)
			(layer "F.SilkS")
		)
		(fp_line
			(start -0.7874 -0.4064)
			(end 0.7874 -0.4064)
			(stroke
				(width 0.1524)
				(type default)
			)
			(layer "F.SilkS")
		)
		(fp_line
			(start 0.67945 0.3048)
			(end 0.120396 0.3048)
			(stroke
				(width 0.1)
				(type default)
			)
			(layer "F.Fab")
		)
		(fp_line
			(start 0.67945 -0.3048)
			(end 0.67945 0.3048)
			(stroke
				(width 0.1)
				(type default)
			)
			(layer "F.Fab")
		)
		(fp_line
			(start 0.12065 -0.2794)
			(end 0.12065 -0.3048)
			(stroke
				(width 0.1)
				(type default)
			)
			(layer "F.Fab")
		)
		(fp_line
			(start 0.12065 -0.3048)
			(end 0.67945 -0.3048)
			(stroke
				(width 0.1)
				(type default)
			)
			(layer "F.Fab")
		)
		(fp_line
			(start 0.120396 0.3048)
			(end 0.120396 0.2794)
			(stroke
				(width 0.1)
				(type default)
			)
			(layer "F.Fab")
		)
		(fp_line
			(start 0.120396 0.2794)
			(end -0.12065 0.2794)
			(stroke
				(width 0.1)
				(type default)
			)
			(layer "F.Fab")
		)
		(fp_line
			(start -0.12065 0.3048)
			(end -0.67945 0.3048)
			(stroke
				(width 0.1)
				(type default)
			)
			(layer "F.Fab")
		)
		(fp_line
			(start -0.12065 0.2794)
			(end -0.12065 0.3048)
			(stroke
				(width 0.1)
				(type default)
			)
			(layer "F.Fab")
		)
		(fp_line
			(start -0.12065 -0.2794)
			(end 0.12065 -0.2794)
			(stroke
				(width 0.1)
				(type default)
			)
			(layer "F.Fab")
		)
		(fp_line
			(start -0.12065 -0.305054)
			(end -0.12065 -0.2794)
			(stroke
				(width 0.1)
				(type default)
			)
			(layer "F.Fab")
		)
		(fp_line
			(start -0.67945 0.3048)
			(end -0.67945 -0.305054)
			(stroke
				(width 0.1)
				(type default)
			)
			(layer "F.Fab")
		)
		(fp_line
			(start -0.67945 -0.305054)
			(end -0.12065 -0.305054)
			(stroke
				(width 0.1)
				(type default)
			)
			(layer "F.Fab")
		)
		(pad "1" smd circle
			(at -0.40005 0 180)
			(size 0 0)
			(layers "F.Cu" "F.Mask" "F.Paste")
			(net "P3V3_AUX")
		)
		(pad "2" smd circle
			(at 0.40005 0 180)
			(size 0 0)
			(layers "F.Cu" "F.Mask" "F.Paste")
			(net "P0V9_RETIMER_CPU1_SVID_SDA")
		)
	)
	(footprint ""
		(layer "F.Cu")
		(at 432.085496 -109.13745 90)
		(property "Reference" "PR3780"
			(at 0 0 90)
			(layer "F.SilkS")
			(hide yes)
			(effects
				(font
					(size 1.27 1.27)
				)
			)
		)
		(property "Value" ""
			(at 0 0 90)
			(layer "F.Fab")
			(effects
				(font
					(size 1.27 1.27)
				)
			)
		)
		(duplicate_pad_numbers_are_jumpers no)
		(fp_line
			(start 0.7874 -0.4064)
			(end 0.7874 0.4064)
			(stroke
				(width 0.1524)
				(type default)
			)
			(layer "F.SilkS")
		)
		(fp_line
			(start -0.7874 -0.4064)
			(end 0.7874 -0.4064)
			(stroke
				(width 0.1524)
				(type default)
			)
			(layer "F.SilkS")
		)
		(fp_line
			(start 0.7874 0.4064)
			(end -0.7874 0.4064)
			(stroke
				(width 0.1524)
				(type default)
			)
			(layer "F.SilkS")
		)
		(fp_line
			(start -0.7874 0.4064)
			(end -0.7874 -0.4064)
			(stroke
				(width 0.1524)
				(type default)
			)
			(layer "F.SilkS")
		)
		(fp_line
			(start -0.12065 -0.305054)
			(end -0.12065 -0.2794)
			(stroke
				(width 0.1)
				(type default)
			)
			(layer "F.Fab")
		)
		(fp_line
			(start -0.67945 -0.305054)
			(end -0.12065 -0.305054)
			(stroke
				(width 0.1)
				(type default)
			)
			(layer "F.Fab")
		)
		(fp_line
			(start 0.67945 -0.3048)
			(end 0.67945 0.3048)
			(stroke
				(width 0.1)
				(type default)
			)
			(layer "F.Fab")
		)
		(fp_line
			(start 0.12065 -0.3048)
			(end 0.67945 -0.3048)
			(stroke
				(width 0.1)
				(type default)
			)
			(layer "F.Fab")
		)
		(fp_line
			(start 0.12065 -0.2794)
			(end 0.12065 -0.3048)
			(stroke
				(width 0.1)
				(type default)
			)
			(layer "F.Fab")
		)
		(fp_line
			(start -0.12065 -0.2794)
			(end 0.12065 -0.2794)
			(stroke
				(width 0.1)
				(type default)
			)
			(layer "F.Fab")
		)
		(fp_line
			(start 0.120396 0.2794)
			(end -0.12065 0.2794)
			(stroke
				(width 0.1)
				(type default)
			)
			(layer "F.Fab")
		)
		(fp_line
			(start -0.12065 0.2794)
			(end -0.12065 0.3048)
			(stroke
				(width 0.1)
				(type default)
			)
			(layer "F.Fab")
		)
		(fp_line
			(start 0.67945 0.3048)
			(end 0.120396 0.3048)
			(stroke
				(width 0.1)
				(type default)
			)
			(layer "F.Fab")
		)
		(fp_line
			(start 0.120396 0.3048)
			(end 0.120396 0.2794)
			(stroke
				(width 0.1)
				(type default)
			)
			(layer "F.Fab")
		)
		(fp_line
			(start -0.12065 0.3048)
			(end -0.67945 0.3048)
			(stroke
				(width 0.1)
				(type default)
			)
			(layer "F.Fab")
		)
		(fp_line
			(start -0.67945 0.3048)
			(end -0.67945 -0.305054)
			(stroke
				(width 0.1)
				(type default)
			)
			(layer "F.Fab")
		)
		(pad "1" smd circle
			(at -0.40005 0 90)
			(size 0 0)
			(layers "F.Cu" "F.Mask" "F.Paste")
			(net "P3V3_OCP_CB_1")
		)
		(pad "2" smd circle
			(at 0.40005 0 90)
			(size 0 0)
			(layers "F.Cu" "F.Mask" "F.Paste")
			(net "GND")
		)
	)
)
